# T6G (Grand Teton) — schematic netlist excerpt (pin names and nets, part order shuffled) for the footprints in the layout excerpt that follows; sources: Cadence DE-HDL packaged netlist, KiCad conversion of 04192023_DAF0TMB3IC0_F0TG_MB_C_brd_V02_OCP.brd

PR3953  Q_RES  120K 1% CHIP  pkg 0402LF  page 147 : A = P12V_AUX ; B = P12V_E1S_OV_FB_0
D46  Q_LED  IC  pkg SMLF  page 166 : A = PU_P12V_ALL_PWROK_LED ; C = P12V_ALL_PWROK_N

(kicad_pcb
	(version 20260206)
	(generator "pcbnew")
	(generator_version "10.0")
	(general
		(thickness 1.6)
		(legacy_teardrops no)
	)
	(paper "A4")
	(title_block
		(title "04192023_DAF0TMB3IC0_F0TG_MB_C_brd_V02_OCP.brd")
		(comment 1 "Grand Teton / footprints 4697-4698 of 8354")
	)
	(layers
		(0 "F.Cu" signal "TOP")
		(4 "In1.Cu" signal "GND")
		(6 "In2.Cu" signal "IN1")
		(8 "In3.Cu" signal "GND1")
		(10 "In4.Cu" signal "IN2")
		(12 "In5.Cu" signal "GND2")
		(14 "In6.Cu" signal "IN3")
		(16 "In7.Cu" signal "GND3")
		(18 "In8.Cu" signal "VCC")
		(20 "In9.Cu" signal "VCC1")
		(22 "In10.Cu" signal "GND4")
		(24 "In11.Cu" signal "IN4")
		(26 "In12.Cu" signal "GND5")
		(28 "In13.Cu" signal "IN5")
		(30 "In14.Cu" signal "GND6")
		(32 "In15.Cu" signal "IN6")
		(34 "In16.Cu" signal "GND7")
		(2 "B.Cu" signal "BOTTOM")
		(9 "F.Adhes" user "F.Adhesive")
		(11 "B.Adhes" user "B.Adhesive")
		(13 "F.Paste" user "Package Geometry/Pastemask Top")
		(15 "B.Paste" user "Package Geometry/Pastemask Bottom")
		(5 "F.SilkS" user "Ref Des/Silkscreen Top")
		(7 "B.SilkS" user "Ref Des/Silkscreen Bottom")
		(1 "F.Mask" user "Board Geometry/Soldermask Top")
		(3 "B.Mask" user "Board Geometry/Soldermask Bottom")
		(17 "Dwgs.User" user "User.Drawings")
		(19 "Cmts.User" user "User.Comments")
		(21 "Eco1.User" user "User.Eco1")
		(23 "Eco2.User" user "User.Eco2")
		(25 "Edge.Cuts" user "Board Geometry/Outline")
		(27 "Margin" user)
		(31 "F.CrtYd" user "Package Geometry/Place Bound Top")
		(29 "B.CrtYd" user "Package Geometry/Place Bound Bottom")
		(35 "F.Fab" user "Ref Des/Assembly Top")
		(33 "B.Fab" user "Ref Des/Assembly Bottom")
	)
	(footprint ""
		(layer "F.Cu")
		(at 348.9325 -15.924276 90)
		(property "Reference" "D46"
			(at -3.12674 0.141732 90)
			(unlocked yes)
			(layer "F.SilkS")
			(effects
				(font
					(size 0.7874 0.5842)
					(thickness 0.1524)
				)
				(justify left)
			)
		)
		(property "Value" ""
			(at 0 0 90)
			(layer "F.Fab")
			(effects
				(font
					(size 1.27 1.27)
				)
			)
		)
		(duplicate_pad_numbers_are_jumpers no)
		(fp_line
			(start 1.16078 -0.4826)
			(end 1.16078 0.4826)
			(stroke
				(width 0.1524)
				(type default)
			)
			(layer "F.SilkS")
		)
		(fp_line
			(start 1.03378 -0.4826)
			(end 1.03378 0.4826)
			(stroke
				(width 0.1524)
				(type default)
			)
			(layer "F.SilkS")
		)
		(fp_line
			(start 0.90678 -0.4826)
			(end 0.90678 0.4826)
			(stroke
				(width 0.1524)
				(type default)
			)
			(layer "F.SilkS")
		)
		(fp_line
			(start -0.64008 -0.4826)
			(end 1.16078 -0.4826)
			(stroke
				(width 0.1524)
				(type default)
			)
			(layer "F.SilkS")
		)
		(fp_line
			(start -0.79248 -0.4826)
			(end 1.03378 -0.4826)
			(stroke
				(width 0.1524)
				(type default)
			)
			(layer "F.SilkS")
		)
		(fp_line
			(start -0.89408 -0.4826)
			(end 0.90678 -0.4826)
			(stroke
				(width 0.1524)
				(type default)
			)
			(layer "F.SilkS")
		)
		(fp_line
			(start 1.16078 0.4826)
			(end -0.64008 0.4826)
			(stroke
				(width 0.1524)
				(type default)
			)
			(layer "F.SilkS")
		)
		(fp_line
			(start 1.03378 0.4826)
			(end -0.79248 0.4826)
			(stroke
				(width 0.1524)
				(type default)
			)
			(layer "F.SilkS")
		)
		(fp_line
			(start 0.90678 0.4826)
			(end -0.90678 0.4826)
			(stroke
				(width 0.1524)
				(type default)
			)
			(layer "F.SilkS")
		)
		(fp_line
			(start -0.90678 0.4826)
			(end -0.90678 -0.4699)
			(stroke
				(width 0.1524)
				(type default)
			)
			(layer "F.SilkS")
		)
		(fp_line
			(start 0.499872 -0.249936)
			(end 0.499872 0.249936)
			(stroke
				(width 0.1)
				(type default)
			)
			(layer "F.Fab")
		)
		(fp_line
			(start -0.499872 -0.249936)
			(end 0.499872 -0.249936)
			(stroke
				(width 0.1)
				(type default)
			)
			(layer "F.Fab")
		)
		(fp_line
			(start 0.499872 0.249936)
			(end -0.499872 0.249936)
			(stroke
				(width 0.1)
				(type default)
			)
			(layer "F.Fab")
		)
		(fp_line
			(start -0.499872 0.249936)
			(end -0.499872 -0.249936)
			(stroke
				(width 0.1)
				(type default)
			)
			(layer "F.Fab")
		)
		(pad "A" smd rect
			(at -0.47498 0 90)
			(size 0.6096 0.7112)
			(layers "F.Cu" "F.Mask" "F.Paste")
			(net "PU_P12V_ALL_PWROK_LED")
		)
		(pad "C" smd rect
			(at 0.47498 0 90)
			(size 0.6096 0.7112)
			(layers "F.Cu" "F.Mask" "F.Paste")
			(net "P12V_ALL_PWROK_N")
		)
	)
	(footprint ""
		(layer "F.Cu")
		(at 252.961648 -56.193182)
		(property "Reference" "PR3953"
			(at 0 0 0)
			(layer "F.SilkS")
			(hide yes)
			(effects
				(font
					(size 1.27 1.27)
				)
			)
		)
		(property "Value" ""
			(at 0 0 0)
			(layer "F.Fab")
			(effects
				(font
					(size 1.27 1.27)
				)
			)
		)
		(duplicate_pad_numbers_are_jumpers no)
		(fp_line
			(start -0.7874 -0.4064)
			(end 0.7874 -0.4064)
			(stroke
				(width 0.1524)
				(type default)
			)
			(layer "F.SilkS")
		)
		(fp_line
			(start -0.7874 0.4064)
			(end -0.7874 -0.4064)
			(stroke
				(width 0.1524)
				(type default)
			)
			(layer "F.SilkS")
		)
		(fp_line
			(start 0.7874 -0.4064)
			(end 0.7874 0.4064)
			(stroke
				(width 0.1524)
				(type default)
			)
			(layer "F.SilkS")
		)
		(fp_line
			(start 0.7874 0.4064)
			(end -0.7874 0.4064)
			(stroke
				(width 0.1524)
				(type default)
			)
			(layer "F.SilkS")
		)
		(fp_line
			(start -0.67945 -0.305054)
			(end -0.12065 -0.305054)
			(stroke
				(width 0.1)
				(type default)
			)
			(layer "F.Fab")
		)
		(fp_line
			(start -0.67945 0.3048)
			(end -0.67945 -0.305054)
			(stroke
				(width 0.1)
				(type default)
			)
			(layer "F.Fab")
		)
		(fp_line
			(start -0.12065 -0.305054)
			(end -0.12065 -0.2794)
			(stroke
				(width 0.1)
				(type default)
			)
			(layer "F.Fab")
		)
		(fp_line
			(start -0.12065 -0.2794)
			(end 0.12065 -0.2794)
			(stroke
				(width 0.1)
				(type default)
			)
			(layer "F.Fab")
		)
		(fp_line
			(start -0.12065 0.2794)
			(end -0.12065 0.3048)
			(stroke
				(width 0.1)
				(type default)
			)
			(layer "F.Fab")
		)
		(fp_line
			(start -0.12065 0.3048)
			(end -0.67945 0.3048)
			(stroke
				(width 0.1)
				(type default)
			)
			(layer "F.Fab")
		)
		(fp_line
			(start 0.120396 0.2794)
			(end -0.12065 0.2794)
			(stroke
				(width 0.1)
				(type default)
			)
			(layer "F.Fab")
		)
		(fp_line
			(start 0.120396 0.3048)
			(end 0.120396 0.2794)
			(stroke
				(width 0.1)
				(type default)
			)
			(layer "F.Fab")
		)
		(fp_line
			(start 0.12065 -0.3048)
			(end 0.67945 -0.3048)
			(stroke
				(width 0.1)
				(type default)
			)
			(layer "F.Fab")
		)
		(fp_line
			(start 0.12065 -0.2794)
			(end 0.12065 -0.3048)
			(stroke
				(width 0.1)
				(type default)
			)
			(layer "F.Fab")
		)
		(fp_line
			(start 0.67945 -0.3048)
			(end 0.67945 0.3048)
			(stroke
				(width 0.1)
				(type default)
			)
			(layer "F.Fab")
		)
		(fp_line
			(start 0.67945 0.3048)
			(end 0.120396 0.3048)
			(stroke
				(width 0.1)
				(type default)
			)
			(layer "F.Fab")
		)
		(pad "1" smd circle
			(at -0.40005 0)
			(size 0 0)
			(layers "F.Cu" "F.Mask" "F.Paste")
			(net "P12V_AUX")
		)
		(pad "2" smd circle
			(at 0.40005 0)
			(size 0 0)
			(layers "F.Cu" "F.Mask" "F.Paste")
			(net "P12V_E1S_OV_FB_0")
		)
	)
)
